(kicad_pcb
	(version 20260206)
	(generator "pcbnew")
	(generator_version "10.0")
	(general
		(thickness 1.6)
		(legacy_teardrops no)
	)
	(paper "A4")
	(title_block
		(title "Bryce Canyon_R.DPB_16317-1_OCP.brd")
		(comment 1 "Bryce Canyon / footprints 1505-1511 of 2099")
	)
	(layers
		(0 "F.Cu" signal "TOP")
		(4 "In1.Cu" signal "L2GND")
		(6 "In2.Cu" signal "L3")
		(8 "In3.Cu" signal "L4VCC")
		(10 "In4.Cu" signal "L5VCC")
		(12 "In5.Cu" signal "L6")
		(14 "In6.Cu" signal "L7GND")
		(2 "B.Cu" signal "BOTTOM")
		(9 "F.Adhes" user "F.Adhesive")
		(11 "B.Adhes" user "B.Adhesive")
		(13 "F.Paste" user "Package Geometry/Pastemask Top")
		(15 "B.Paste" user "Package Geometry/Pastemask Bottom")
		(5 "F.SilkS" user "Ref Des/Silkscreen Top")
		(7 "B.SilkS" user "Ref Des/Silkscreen Bottom")
		(1 "F.Mask" user "Board Geometry/Soldermask Top")
		(3 "B.Mask" user "Board Geometry/Soldermask Bottom")
		(17 "Dwgs.User" user "User.Drawings")
		(19 "Cmts.User" user "User.Comments")
		(21 "Eco1.User" user "User.Eco1")
		(23 "Eco2.User" user "User.Eco2")
		(25 "Edge.Cuts" user "Board Geometry/Outline")
		(27 "Margin" user)
		(31 "F.CrtYd" user "Package Geometry/Place Bound Top")
		(29 "B.CrtYd" user "Package Geometry/Place Bound Bottom")
		(35 "F.Fab" user "Ref Des/Assembly Top")
		(33 "B.Fab" user "Ref Des/Assembly Bottom")
	)
	(footprint ""
		(layer "F.Cu")
		(at 20.066 -32.004 -90)
		(property "Reference" "C343"
			(at 0 0 270)
			(layer "F.SilkS")
			(hide yes)
			(effects
				(font
					(size 1.27 1.27)
				)
			)
		)
		(property "Value" "SC10U16V6KX-2GP"
			(at -0.0762 -5.1308 270)
			(unlocked yes)
			(layer "F.Fab")
			(hide yes)
			(effects
				(font
					(size 1.016 1.016)
					(thickness 0.1524)
				)
			)
		)
		(property "Device Type" "C1206H71"
			(at -0.127 -6.6548 270)
			(unlocked yes)
			(layer "F.Fab")
			(hide yes)
			(effects
				(font
					(size 1.016 1.016)
					(thickness 0.1524)
				)
			)
		)
		(duplicate_pad_numbers_are_jumpers no)
		(fp_line
			(start -1.016 2.2352)
			(end -1.016 0.8382)
			(stroke
				(width 0.1524)
				(type default)
			)
			(layer "F.SilkS")
		)
		(fp_line
			(start 1.016 2.2352)
			(end -1.016 2.2352)
			(stroke
				(width 0.1524)
				(type default)
			)
			(layer "F.SilkS")
		)
		(fp_line
			(start 1.016 0.8382)
			(end 1.016 2.2352)
			(stroke
				(width 0.1524)
				(type default)
			)
			(layer "F.SilkS")
		)
		(fp_line
			(start -1.016 -0.8382)
			(end -1.016 -2.2352)
			(stroke
				(width 0.1524)
				(type default)
			)
			(layer "F.SilkS")
		)
		(fp_line
			(start -1.016 -2.2352)
			(end 1.016 -2.2352)
			(stroke
				(width 0.1524)
				(type default)
			)
			(layer "F.SilkS")
		)
		(fp_line
			(start 1.016 -2.2352)
			(end 1.016 -0.8382)
			(stroke
				(width 0.1524)
				(type default)
			)
			(layer "F.SilkS")
		)
		(fp_rect
			(start -1.0922 2.3114)
			(end 1.0922 -2.3114)
			(stroke
				(width 0)
				(type default)
			)
			(fill no)
			(layer "F.CrtYd")
		)
		(fp_poly
			(pts
				(xy 1.0922 -2.3114) (xy 1.0922 2.3114) (xy -1.0922 2.3114) (xy -1.0922 -2.3114)
			)
			(stroke
				(width 0)
				(type default)
			)
			(fill no)
			(layer "F.Fab")
		)
		(pad "1" smd rect
			(at 0 -1.397 270)
			(size 1.651 1.27)
			(layers "F.Cu" "F.Mask" "F.Paste")
			(net "P5V_HDD24")
		)
		(pad "2" smd rect
			(at 0 1.397 270)
			(size 1.651 1.27)
			(layers "F.Cu" "F.Mask" "F.Paste")
			(net "GND")
		)
	)
	(footprint ""
		(layer "F.Cu")
		(at 146.685 -19.558 180)
		(property "Reference" "Q143"
			(at 0 0 180)
			(layer "F.SilkS")
			(hide yes)
			(effects
				(font
					(size 1.27 1.27)
				)
			)
		)
		(property "Value" "2N7002KDW-GP"
			(at -2.3622 -8.2042 180)
			(unlocked yes)
			(layer "F.Fab")
			(hide yes)
			(effects
				(font
					(size 1.016 1.016)
					(thickness 0.1524)
				)
			)
		)
		(property "Device Type" "SOT-363H44"
			(at -2.3622 -10.1092 180)
			(unlocked yes)
			(layer "F.Fab")
			(hide yes)
			(effects
				(font
					(size 1.016 1.016)
					(thickness 0.1524)
				)
			)
		)
		(duplicate_pad_numbers_are_jumpers no)
		(fp_line
			(start 1.4478 1.7018)
			(end 1.4478 -1.7018)
			(stroke
				(width 0.1524)
				(type default)
			)
			(layer "F.SilkS")
		)
		(fp_line
			(start 1.4478 -1.7018)
			(end -1.4478 -1.7018)
			(stroke
				(width 0.1524)
				(type default)
			)
			(layer "F.SilkS")
		)
		(fp_line
			(start -1.27 1.524)
			(end -1.27 0.6604)
			(stroke
				(width 0.4826)
				(type default)
			)
			(layer "F.SilkS")
		)
		(fp_line
			(start -1.4478 1.7018)
			(end 1.4478 1.7018)
			(stroke
				(width 0.1524)
				(type default)
			)
			(layer "F.SilkS")
		)
		(fp_line
			(start -1.4478 -1.7018)
			(end -1.4478 1.7018)
			(stroke
				(width 0.1524)
				(type default)
			)
			(layer "F.SilkS")
		)
		(fp_poly
			(pts
				(xy -1.524 -1.778) (xy 1.524 -1.778) (xy 1.524 1.778) (xy -1.524 1.778)
			)
			(stroke
				(width 0)
				(type default)
			)
			(fill no)
			(layer "F.CrtYd")
		)
		(fp_poly
			(pts
				(xy -1.524 -1.778) (xy 1.524 -1.778) (xy 1.524 1.778) (xy -1.524 1.778)
			)
			(stroke
				(width 0)
				(type default)
			)
			(fill no)
			(layer "F.Fab")
		)
		(pad "1" smd rect
			(at -0.65024 0.9398 180)
			(size 0.4064 1.016)
			(layers "F.Cu" "F.Mask" "F.Paste")
			(net "GND")
		)
		(pad "2" smd rect
			(at 0 0.9398 180)
			(size 0.4064 1.016)
			(layers "F.Cu" "F.Mask" "F.Paste")
			(net "SW_PWR_R_HDD28")
		)
		(pad "3" smd rect
			(at 0.65024 0.9398 180)
			(size 0.4064 1.016)
			(layers "F.Cu" "F.Mask" "F.Paste")
			(net "SW_HDD_P28")
		)
		(pad "4" smd rect
			(at 0.65024 -0.9398 180)
			(size 0.4064 1.016)
			(layers "F.Cu" "F.Mask" "F.Paste")
			(net "GND")
		)
		(pad "5" smd rect
			(at 0 -0.9398 180)
			(size 0.4064 1.016)
			(layers "F.Cu" "F.Mask" "F.Paste")
			(net "SW_HDD_G28")
		)
		(pad "6" smd rect
			(at -0.65024 -0.9398 180)
			(size 0.4064 1.016)
			(layers "F.Cu" "F.Mask" "F.Paste")
			(net "SW_HDD_R28")
		)
	)
	(footprint ""
		(layer "F.Cu")
		(at 287.048448 -347.541342)
		(property "Reference" "R1079"
			(at 0 0 0)
			(layer "F.SilkS")
			(hide yes)
			(effects
				(font
					(size 1.27 1.27)
				)
			)
		)
		(property "Value" "0R2J-2-GP"
			(at 0.064008 -3.993896 0)
			(unlocked yes)
			(layer "F.Fab")
			(hide yes)
			(effects
				(font
					(size 1.016 1.016)
					(thickness 0.1524)
				)
			)
		)
		(property "Device Type" "R402H16"
			(at 0.064008 -5.517896 0)
			(unlocked yes)
			(layer "F.Fab")
			(hide yes)
			(effects
				(font
					(size 1.016 1.016)
					(thickness 0.1524)
				)
			)
		)
		(duplicate_pad_numbers_are_jumpers no)
		(fp_line
			(start -0.508 -0.9398)
			(end -0.508 0.9398)
			(stroke
				(width 0.1524)
				(type default)
			)
			(layer "F.SilkS")
		)
		(fp_line
			(start 0.508 -0.9398)
			(end -0.508 -0.9398)
			(stroke
				(width 0.1524)
				(type default)
			)
			(layer "F.SilkS")
		)
		(fp_rect
			(start -0.508 0.9398)
			(end 0.508 -0.9398)
			(stroke
				(width 0)
				(type default)
			)
			(fill no)
			(layer "F.CrtYd")
		)
		(fp_rect
			(start -0.508 0.9398)
			(end 0.508 -0.9398)
			(stroke
				(width 0)
				(type default)
			)
			(fill no)
			(layer "F.Fab")
		)
		(pad "1" smd custom
			(at 0 -0.4445)
			(size 0.1397 0.1397)
			(layers "F.Cu" "F.Mask" "F.Paste")
			(net "MAX31790_B_ADD0")
			(options
				(clearance outline)
				(anchor circle)
			)
			(primitives
				(gr_poly
					(pts
						(arc
							(start -0.1778 -0.2794)
							(mid -0.249642 -0.249642)
							(end -0.2794 -0.1778)
						)
						(arc
							(start -0.2794 0.1778)
							(mid -0.249642 0.249642)
							(end -0.1778 0.2794)
						)
						(arc
							(start 0.1778 0.2794)
							(mid 0.249642 0.249642)
							(end 0.2794 0.1778)
						)
						(arc
							(start 0.2794 -0.1778)
							(mid 0.249642 -0.249642)
							(end 0.1778 -0.2794)
						)
					)
					(width 0)
					(fill yes)
				)
			)
		)
		(pad "2" smd custom
			(at 0 0.4445)
			(size 0.1397 0.1397)
			(layers "F.Cu" "F.Mask" "F.Paste")
			(net "GND")
			(options
				(clearance outline)
				(anchor circle)
			)
			(primitives
				(gr_poly
					(pts
						(arc
							(start -0.1778 -0.2794)
							(mid -0.249642 -0.249642)
							(end -0.2794 -0.1778)
						)
						(arc
							(start -0.2794 0.1778)
							(mid -0.249642 0.249642)
							(end -0.1778 0.2794)
						)
						(arc
							(start 0.1778 0.2794)
							(mid 0.249642 0.249642)
							(end 0.2794 0.1778)
						)
						(arc
							(start 0.2794 -0.1778)
							(mid 0.249642 -0.249642)
							(end 0.1778 -0.2794)
						)
					)
					(width 0)
					(fill yes)
				)
			)
		)
	)
	(footprint ""
		(layer "F.Cu")
		(at 44.528232 -212.323172 90)
		(property "Reference" "R157"
			(at 0 0 90)
			(layer "F.SilkS")
			(hide yes)
			(effects
				(font
					(size 1.27 1.27)
				)
			)
		)
		(property "Value" "4K7R2F-GP"
			(at 0.064008 -3.993896 90)
			(unlocked yes)
			(layer "F.Fab")
			(hide yes)
			(effects
				(font
					(size 1.016 1.016)
					(thickness 0.1524)
				)
			)
		)
		(property "Device Type" "R402H16"
			(at 0.064008 -5.517896 90)
			(unlocked yes)
			(layer "F.Fab")
			(hide yes)
			(effects
				(font
					(size 1.016 1.016)
					(thickness 0.1524)
				)
			)
		)
		(duplicate_pad_numbers_are_jumpers no)
		(fp_line
			(start 0.508 -0.9398)
			(end -0.508 -0.9398)
			(stroke
				(width 0.1524)
				(type default)
			)
			(layer "F.SilkS")
		)
		(fp_line
			(start -0.508 -0.9398)
			(end -0.508 0.9398)
			(stroke
				(width 0.1524)
				(type default)
			)
			(layer "F.SilkS")
		)
		(fp_rect
			(start -0.508 0.9398)
			(end 0.508 -0.9398)
			(stroke
				(width 0)
				(type default)
			)
			(fill no)
			(layer "F.CrtYd")
		)
		(fp_rect
			(start -0.508 0.9398)
			(end 0.508 -0.9398)
			(stroke
				(width 0)
				(type default)
			)
			(fill no)
			(layer "F.Fab")
		)
		(pad "1" smd custom
			(at 0 -0.4445 90)
			(size 0.1397 0.1397)
			(layers "F.Cu" "F.Mask" "F.Paste")
			(net "DRIVE_B_1_ACT")
			(options
				(clearance outline)
				(anchor circle)
			)
			(primitives
				(gr_poly
					(pts
						(arc
							(start -0.1778 -0.2794)
							(mid -0.249642 -0.249642)
							(end -0.2794 -0.1778)
						)
						(arc
							(start -0.2794 0.1778)
							(mid -0.249642 0.249642)
							(end -0.1778 0.2794)
						)
						(arc
							(start 0.1778 0.2794)
							(mid 0.249642 0.249642)
							(end 0.2794 0.1778)
						)
						(arc
							(start 0.2794 -0.1778)
							(mid 0.249642 -0.249642)
							(end 0.1778 -0.2794)
						)
					)
					(width 0)
					(fill yes)
				)
			)
		)
		(pad "2" smd custom
			(at 0 0.4445 90)
			(size 0.1397 0.1397)
			(layers "F.Cu" "F.Mask" "F.Paste")
			(net "GND")
			(options
				(clearance outline)
				(anchor circle)
			)
			(primitives
				(gr_poly
					(pts
						(arc
							(start -0.1778 -0.2794)
							(mid -0.249642 -0.249642)
							(end -0.2794 -0.1778)
						)
						(arc
							(start -0.2794 0.1778)
							(mid -0.249642 0.249642)
							(end -0.1778 0.2794)
						)
						(arc
							(start 0.1778 0.2794)
							(mid 0.249642 0.249642)
							(end 0.2794 0.1778)
						)
						(arc
							(start 0.2794 -0.1778)
							(mid 0.249642 -0.249642)
							(end 0.1778 -0.2794)
						)
					)
					(width 0)
					(fill yes)
				)
			)
		)
	)
	(footprint ""
		(layer "F.Cu")
		(at 77.978 -25.527 90)
		(property "Reference" "C377"
			(at 0 0 90)
			(layer "F.SilkS")
			(hide yes)
			(effects
				(font
					(size 1.27 1.27)
				)
			)
		)
		(property "Value" "SCD033U25V2KX-GP"
			(at 1.1811 -2.7051 90)
			(unlocked yes)
			(layer "F.Fab")
			(hide yes)
			(effects
				(font
					(size 1.016 1.016)
					(thickness 0.1524)
				)
			)
		)
		(property "Device Type" "C402H22"
			(at 1.1811 -4.2291 90)
			(unlocked yes)
			(layer "F.Fab")
			(hide yes)
			(effects
				(font
					(size 1.016 1.016)
					(thickness 0.1524)
				)
			)
		)
		(duplicate_pad_numbers_are_jumpers no)
		(fp_rect
			(start -0.4318 0.9525)
			(end 0.4318 -0.9525)
			(stroke
				(width 0)
				(type default)
			)
			(fill no)
			(layer "F.CrtYd")
		)
		(fp_rect
			(start -0.4318 0.9525)
			(end 0.4318 -0.9525)
			(stroke
				(width 0)
				(type default)
			)
			(fill no)
			(layer "F.Fab")
		)
		(pad "1" smd custom
			(at 0 -0.4445 90)
			(size 0.1524 0.1524)
			(layers "F.Cu" "F.Mask" "F.Paste")
			(net "P12V_B")
			(options
				(clearance outline)
				(anchor circle)
			)
			(primitives
				(gr_poly
					(pts
						(arc
							(start 0.3048 -0.2032)
							(mid 0.275042 -0.275042)
							(end 0.2032 -0.3048)
						)
						(arc
							(start -0.2032 -0.3048)
							(mid -0.275042 -0.275042)
							(end -0.3048 -0.2032)
						)
						(arc
							(start -0.3048 0.2032)
							(mid -0.275042 0.275042)
							(end -0.2032 0.3048)
						)
						(arc
							(start 0.2032 0.3048)
							(mid 0.275042 0.275042)
							(end 0.3048 0.2032)
						)
					)
					(width 0)
					(fill yes)
				)
			)
		)
		(pad "2" smd custom
			(at 0 0.4445 90)
			(size 0.1524 0.1524)
			(layers "F.Cu" "F.Mask" "F.Paste")
			(net "SW_HDD_N26")
			(options
				(clearance outline)
				(anchor circle)
			)
			(primitives
				(gr_poly
					(pts
						(arc
							(start 0.3048 -0.2032)
							(mid 0.275042 -0.275042)
							(end 0.2032 -0.3048)
						)
						(arc
							(start -0.2032 -0.3048)
							(mid -0.275042 -0.275042)
							(end -0.3048 -0.2032)
						)
						(arc
							(start -0.3048 0.2032)
							(mid -0.275042 0.275042)
							(end -0.2032 0.3048)
						)
						(arc
							(start 0.2032 0.3048)
							(mid 0.275042 0.275042)
							(end 0.3048 0.2032)
						)
					)
					(width 0)
					(fill yes)
				)
			)
		)
	)
	(footprint ""
		(layer "F.Cu")
		(at 213.35238 -245.91518 180)
		(property "Reference" "R35"
			(at 0 0 180)
			(layer "F.SilkS")
			(hide yes)
			(effects
				(font
					(size 1.27 1.27)
				)
			)
		)
		(property "Value" "0R2J-2-GP"
			(at 0.064008 -3.993896 180)
			(unlocked yes)
			(layer "F.Fab")
			(hide yes)
			(effects
				(font
					(size 1.016 1.016)
					(thickness 0.1524)
				)
			)
		)
		(property "Device Type" "R402H16"
			(at 0.064008 -5.517896 180)
			(unlocked yes)
			(layer "F.Fab")
			(hide yes)
			(effects
				(font
					(size 1.016 1.016)
					(thickness 0.1524)
				)
			)
		)
		(duplicate_pad_numbers_are_jumpers no)
		(fp_line
			(start 0.508 -0.9398)
			(end -0.508 -0.9398)
			(stroke
				(width 0.1524)
				(type default)
			)
			(layer "F.SilkS")
		)
		(fp_line
			(start -0.508 -0.9398)
			(end -0.508 0.9398)
			(stroke
				(width 0.1524)
				(type default)
			)
			(layer "F.SilkS")
		)
		(fp_rect
			(start -0.508 0.9398)
			(end 0.508 -0.9398)
			(stroke
				(width 0)
				(type default)
			)
			(fill no)
			(layer "F.CrtYd")
		)
		(fp_rect
			(start -0.508 0.9398)
			(end 0.508 -0.9398)
			(stroke
				(width 0)
				(type default)
			)
			(fill no)
			(layer "F.Fab")
		)
		(pad "1" smd custom
			(at 0 -0.4445 180)
			(size 0.1397 0.1397)
			(layers "F.Cu" "F.Mask" "F.Paste")
			(net "IO_EXP4_INT_N")
			(options
				(clearance outline)
				(anchor circle)
			)
			(primitives
				(gr_poly
					(pts
						(arc
							(start -0.1778 -0.2794)
							(mid -0.249642 -0.249642)
							(end -0.2794 -0.1778)
						)
						(arc
							(start -0.2794 0.1778)
							(mid -0.249642 0.249642)
							(end -0.1778 0.2794)
						)
						(arc
							(start 0.1778 0.2794)
							(mid 0.249642 0.249642)
							(end 0.2794 0.1778)
						)
						(arc
							(start 0.2794 -0.1778)
							(mid 0.249642 -0.249642)
							(end 0.1778 -0.2794)
						)
					)
					(width 0)
					(fill yes)
				)
			)
		)
		(pad "2" smd custom
			(at 0 0.4445 180)
			(size 0.1397 0.1397)
			(layers "F.Cu" "F.Mask" "F.Paste")
			(net "DRIVE_INSERT_ALERT_B_N")
			(options
				(clearance outline)
				(anchor circle)
			)
			(primitives
				(gr_poly
					(pts
						(arc
							(start -0.1778 -0.2794)
							(mid -0.249642 -0.249642)
							(end -0.2794 -0.1778)
						)
						(arc
							(start -0.2794 0.1778)
							(mid -0.249642 0.249642)
							(end -0.1778 0.2794)
						)
						(arc
							(start 0.1778 0.2794)
							(mid 0.249642 0.249642)
							(end 0.2794 0.1778)
						)
						(arc
							(start 0.2794 -0.1778)
							(mid 0.249642 -0.249642)
							(end 0.1778 -0.2794)
						)
					)
					(width 0)
					(fill yes)
				)
			)
		)
	)
	(footprint ""
		(layer "F.Cu")
		(at 416.1028 -146.6342)
		(property "Reference" "C310"
			(at 0 0 0)
			(layer "F.SilkS")
			(hide yes)
			(effects
				(font
					(size 1.27 1.27)
				)
			)
		)
		(property "Value" "SCD01U50V2KX-1GP"
			(at 1.1811 -2.7051 0)
			(unlocked yes)
			(layer "F.Fab")
			(hide yes)
			(effects
				(font
					(size 1.016 1.016)
					(thickness 0.1524)
				)
			)
		)
		(property "Device Type" "C402H22"
			(at 1.1811 -4.2291 0)
			(unlocked yes)
			(layer "F.Fab")
			(hide yes)
			(effects
				(font
					(size 1.016 1.016)
					(thickness 0.1524)
				)
			)
		)
		(duplicate_pad_numbers_are_jumpers no)
		(fp_rect
			(start -0.4318 0.9525)
			(end 0.4318 -0.9525)
			(stroke
				(width 0)
				(type default)
			)
			(fill no)
			(layer "F.CrtYd")
		)
		(fp_rect
			(start -0.4318 0.9525)
			(end 0.4318 -0.9525)
			(stroke
				(width 0)
				(type default)
			)
			(fill no)
			(layer "F.Fab")
		)
		(pad "1" smd custom
			(at 0 -0.4445)
			(size 0.1524 0.1524)
			(layers "F.Cu" "F.Mask" "F.Paste")
			(net "HDD_PRSNT_21")
			(options
				(clearance outline)
				(anchor circle)
			)
			(primitives
				(gr_poly
					(pts
						(arc
							(start 0.3048 -0.2032)
							(mid 0.275042 -0.275042)
							(end 0.2032 -0.3048)
						)
						(arc
							(start -0.2032 -0.3048)
							(mid -0.275042 -0.275042)
							(end -0.3048 -0.2032)
						)
						(arc
							(start -0.3048 0.2032)
							(mid -0.275042 0.275042)
							(end -0.2032 0.3048)
						)
						(arc
							(start 0.2032 0.3048)
							(mid 0.275042 0.275042)
							(end 0.3048 0.2032)
						)
					)
					(width 0)
					(fill yes)
				)
			)
		)
		(pad "2" smd custom
			(at 0 0.4445)
			(size 0.1524 0.1524)
			(layers "F.Cu" "F.Mask" "F.Paste")
			(net "GND")
			(options
				(clearance outline)
				(anchor circle)
			)
			(primitives
				(gr_poly
					(pts
						(arc
							(start 0.3048 -0.2032)
							(mid 0.275042 -0.275042)
							(end 0.2032 -0.3048)
						)
						(arc
							(start -0.2032 -0.3048)
							(mid -0.275042 -0.275042)
							(end -0.3048 -0.2032)
						)
						(arc
							(start -0.3048 0.2032)
							(mid -0.275042 0.275042)
							(end -0.2032 0.3048)
						)
						(arc
							(start 0.2032 0.3048)
							(mid 0.275042 0.275042)
							(end 0.3048 0.2032)
						)
					)
					(width 0)
					(fill yes)
				)
			)
		)
	)
)
